(kicad_pcb
	(version 20260206)
	(generator "pcbnew")
	(generator_version "10.0")
	(general
		(thickness 1.6)
		(legacy_teardrops no)
	)
	(paper "A4")
	(title_block
		(title "03242023_DA0F0TMBIJ0_F0T_Motherboard_J_brd_V01_OCP.brd")
		(comment 1 "Grand Teton / footprint 3039 of 6105 (U2), pads 1602-1707 of 4677")
	)
	(layers
		(0 "F.Cu" signal "TOP")
		(4 "In1.Cu" signal "GND")
		(6 "In2.Cu" signal "IN1")
		(8 "In3.Cu" signal "GND1")
		(10 "In4.Cu" signal "IN2")
		(12 "In5.Cu" signal "GND2")
		(14 "In6.Cu" signal "IN3")
		(16 "In7.Cu" signal "GND3")
		(18 "In8.Cu" signal "VCC")
		(20 "In9.Cu" signal "VCC1")
		(22 "In10.Cu" signal "GND4")
		(24 "In11.Cu" signal "IN4")
		(26 "In12.Cu" signal "GND5")
		(28 "In13.Cu" signal "IN5")
		(30 "In14.Cu" signal "GND6")
		(32 "In15.Cu" signal "IN6")
		(34 "In16.Cu" signal "GND7")
		(2 "B.Cu" signal "BOTTOM")
		(9 "F.Adhes" user "F.Adhesive")
		(11 "B.Adhes" user "B.Adhesive")
		(13 "F.Paste" user "Package Geometry/Pastemask Top")
		(15 "B.Paste" user "Package Geometry/Pastemask Bottom")
		(5 "F.SilkS" user "Ref Des/Silkscreen Top")
		(7 "B.SilkS" user "Ref Des/Silkscreen Bottom")
		(1 "F.Mask" user "Board Geometry/Soldermask Top")
		(3 "B.Mask" user "Board Geometry/Soldermask Bottom")
		(17 "Dwgs.User" user "User.Drawings")
		(19 "Cmts.User" user "User.Comments")
		(21 "Eco1.User" user "User.Eco1")
		(23 "Eco2.User" user "User.Eco2")
		(25 "Edge.Cuts" user "Board Geometry/Outline")
		(27 "Margin" user)
		(31 "F.CrtYd" user "Package Geometry/Place Bound Top")
		(29 "B.CrtYd" user "Package Geometry/Place Bound Bottom")
		(35 "F.Fab" user "Ref Des/Assembly Top")
		(33 "B.Fab" user "Ref Des/Assembly Bottom")
	)
	(footprint ""
		(layer "F.Cu")
		(at 359.870248 -251.76988 90)
		(property "Reference" "U2"
			(at -74.416158 -44.488608 0)
			(unlocked yes)
			(layer "F.SilkS")
			(effects
				(font
					(size 1.6002 1.1938)
					(thickness 0.1524)
				)
				(justify left)
			)
		)
		(property "Value" ""
			(at 0 0 90)
			(layer "F.Fab")
			(effects
				(font
					(size 1.27 1.27)
				)
			)
		)
		(duplicate_pad_numbers_are_jumpers no)
		(pad "BY24" smd circle
			(at -18.705576 0.649732 270)
			(size 0.4318 0.4318)
			(layers "F.Cu" "F.Mask" "F.Paste")
			(net "PD_EXT_CLK_SEL_CPU0")
		)
		(pad "BY26" smd circle
			(at -17.07769 0.649732 270)
			(size 0.4318 0.4318)
			(layers "F.Cu" "F.Mask" "F.Paste")
			(net "SMB_PEHPCPU0_GTL_SDA")
		)
		(pad "BY28" smd circle
			(at -15.450058 0.649732 270)
			(size 0.4318 0.4318)
			(layers "F.Cu" "F.Mask" "F.Paste")
			(net "TP_TRC_CPU0_PTI1_CLK")
		)
		(pad "BY30" smd circle
			(at -13.822426 0.649732 270)
			(size 0.4318 0.4318)
			(layers "F.Cu" "F.Mask" "F.Paste")
			(net "TP_TRC_CPU0_PTI<3>")
		)
		(pad "BY32" smd circle
			(at -12.19454 0.649732 270)
			(size 0.4318 0.4318)
			(layers "F.Cu" "F.Mask" "F.Paste")
			(net "PVCCIN_CPU0")
		)
		(pad "BY34" smd circle
			(at -10.566654 0.649732 270)
			(size 0.4318 0.4318)
			(layers "F.Cu" "F.Mask" "F.Paste")
			(net "PVCCIN_CPU0")
		)
		(pad "BY36" smd circle
			(at -8.939022 0.649732 270)
			(size 0.4318 0.4318)
			(layers "F.Cu" "F.Mask" "F.Paste")
			(net "PVCCIN_CPU0")
		)
		(pad "BY38" smd circle
			(at -7.311136 0.649732 270)
			(size 0.4318 0.4318)
			(layers "F.Cu" "F.Mask" "F.Paste")
			(net "PVCCIN_CPU0")
		)
		(pad "BY40" smd circle
			(at -5.68325 0.649732 270)
			(size 0.4318 0.4318)
			(layers "F.Cu" "F.Mask" "F.Paste")
			(net "PVCCIN_CPU0")
		)
		(pad "BY42" smd circle
			(at -4.055618 0.649732 270)
			(size 0.4318 0.4318)
			(layers "F.Cu" "F.Mask" "F.Paste")
			(net "PVCCIN_CPU0")
		)
		(pad "BY44" smd circle
			(at -2.427732 0.649732 270)
			(size 0.4318 0.4318)
			(layers "F.Cu" "F.Mask" "F.Paste")
			(net "PVCCIN_CPU0")
		)
		(pad "BY47" smd circle
			(at 1.613916 0.759714 270)
			(size 0.4318 0.4318)
			(layers "F.Cu" "F.Mask" "F.Paste")
			(net "PVCCIN_CPU0")
		)
		(pad "BY49" smd circle
			(at 3.241802 0.759714 270)
			(size 0.4318 0.4318)
			(layers "F.Cu" "F.Mask" "F.Paste")
			(net "PVCCIN_CPU0")
		)
		(pad "BY51" smd circle
			(at 4.869434 0.759714 270)
			(size 0.4318 0.4318)
			(layers "F.Cu" "F.Mask" "F.Paste")
			(net "PVCCIN_CPU0")
		)
		(pad "BY53" smd circle
			(at 6.49732 0.759714 270)
			(size 0.4318 0.4318)
			(layers "F.Cu" "F.Mask" "F.Paste")
			(net "PVCCIN_CPU0")
		)
		(pad "BY55" smd circle
			(at 8.124952 0.759714 270)
			(size 0.4318 0.4318)
			(layers "F.Cu" "F.Mask" "F.Paste")
			(net "PVCCIN_CPU0")
		)
		(pad "BY57" smd circle
			(at 9.752838 0.759714 270)
			(size 0.4318 0.4318)
			(layers "F.Cu" "F.Mask" "F.Paste")
			(net "PVCCIN_CPU0")
		)
		(pad "BY59" smd circle
			(at 11.380724 0.759714 270)
			(size 0.4318 0.4318)
			(layers "F.Cu" "F.Mask" "F.Paste")
			(net "PVCCIN_CPU0")
		)
		(pad "BY61" smd circle
			(at 13.008356 0.759714 270)
			(size 0.4318 0.4318)
			(layers "F.Cu" "F.Mask" "F.Paste")
			(net "PVCCIN_CPU0")
		)
		(pad "BY63" smd circle
			(at 14.635988 0.759714 270)
			(size 0.4318 0.4318)
			(layers "F.Cu" "F.Mask" "F.Paste")
			(net "PVCCIN_CPU0")
		)
		(pad "BY65" smd circle
			(at 16.263874 0.759714 270)
			(size 0.4318 0.4318)
			(layers "F.Cu" "F.Mask" "F.Paste")
			(net "PVCCIN_CPU0")
		)
		(pad "BY67" smd circle
			(at 17.89176 0.759714 270)
			(size 0.4318 0.4318)
			(layers "F.Cu" "F.Mask" "F.Paste")
			(net "PVCCIN_CPU0")
		)
		(pad "BY69" smd circle
			(at 19.519392 0.759714 270)
			(size 0.4318 0.4318)
			(layers "F.Cu" "F.Mask" "F.Paste")
			(net "PVCCIN_CPU0")
		)
		(pad "BY71" smd circle
			(at 21.147278 0.759714 270)
			(size 0.4318 0.4318)
			(layers "F.Cu" "F.Mask" "F.Paste")
			(net "PVCCIN_CPU0")
		)
		(pad "BY73" smd circle
			(at 22.77491 0.759714 270)
			(size 0.4318 0.4318)
			(layers "F.Cu" "F.Mask" "F.Paste")
			(net "PVCCIN_CPU0")
		)
		(pad "BY75" smd circle
			(at 24.402796 0.759714 270)
			(size 0.4318 0.4318)
			(layers "F.Cu" "F.Mask" "F.Paste")
			(net "PVCCIN_CPU0")
		)
		(pad "BY77" smd circle
			(at 26.030682 0.759714 270)
			(size 0.4318 0.4318)
			(layers "F.Cu" "F.Mask" "F.Paste")
			(net "PVCCIN_CPU0")
		)
		(pad "BY79" smd circle
			(at 27.658314 0.759714 270)
			(size 0.4318 0.4318)
			(layers "F.Cu" "F.Mask" "F.Paste")
			(net "PVCCIN_CPU0")
		)
		(pad "BY81" smd circle
			(at 29.2862 0.759714 270)
			(size 0.4318 0.4318)
			(layers "F.Cu" "F.Mask" "F.Paste")
			(net "PVCCIN_CPU0")
		)
		(pad "BY83" smd circle
			(at 30.914086 0.759714 270)
			(size 0.4318 0.4318)
			(layers "F.Cu" "F.Mask" "F.Paste")
			(net "PVCCIN_CPU0")
		)
		(pad "BY85" smd circle
			(at 32.541718 0.759714 270)
			(size 0.4318 0.4318)
			(layers "F.Cu" "F.Mask" "F.Paste")
			(net "PVCCIN_CPU0")
		)
		(pad "BY87" smd circle
			(at 34.169604 0.759714 270)
			(size 0.4318 0.4318)
			(layers "F.Cu" "F.Mask" "F.Paste")
			(net "PVCCIN_CPU0")
		)
		(pad "BY89" smd circle
			(at 35.797236 0.759714 270)
			(size 0.4318 0.4318)
			(layers "F.Cu" "F.Mask" "F.Paste")
			(net "PVCCIN_CPU0")
		)
		(pad "C5" smd oval
			(at -34.169604 -26.134314 135)
			(size 0.381 0.4826)
			(drill
				(offset 0 -0.0508)
			)
			(layers "F.Cu" "F.Mask" "F.Paste")
			(net "GND")
		)
		(pad "C7" smd oval
			(at -32.541718 -26.134314 135)
			(size 0.381 0.4826)
			(drill
				(offset 0 -0.0508)
			)
			(layers "F.Cu" "F.Mask" "F.Paste")
			(net "M_A_CPU0_SB_DQ<29>")
		)
		(pad "C9" smd oval
			(at -30.914086 -26.134314 90)
			(size 0.381 0.4826)
			(drill
				(offset 0 -0.0508)
			)
			(layers "F.Cu" "F.Mask" "F.Paste")
			(net "M_A_CPU0_SB_DQS_DP<3>")
		)
		(pad "C11" smd circle
			(at -29.2862 -26.134314 270)
			(size 0.4318 0.4318)
			(layers "F.Cu" "F.Mask" "F.Paste")
			(net "M_A_CPU0_SB_DQ<24>")
		)
		(pad "C13" smd circle
			(at -27.658314 -26.134314 270)
			(size 0.4318 0.4318)
			(layers "F.Cu" "F.Mask" "F.Paste")
			(net "M_B_CPU0_SB_DQ<28>")
		)
		(pad "C15" smd circle
			(at -26.030682 -26.134314 270)
			(size 0.4318 0.4318)
			(layers "F.Cu" "F.Mask" "F.Paste")
			(net "M_B_CPU0_SB_DQS_DP<3>")
		)
		(pad "C17" smd circle
			(at -24.402796 -26.134314 270)
			(size 0.4318 0.4318)
			(layers "F.Cu" "F.Mask" "F.Paste")
			(net "M_B_CPU0_SB_DQ<24>")
		)
		(pad "C19" smd circle
			(at -22.77491 -26.134314 270)
			(size 0.4318 0.4318)
			(layers "F.Cu" "F.Mask" "F.Paste")
			(net "M_A_CPU0_SB_DQ<21>")
		)
		(pad "C21" smd circle
			(at -21.147278 -26.134314 270)
			(size 0.4318 0.4318)
			(layers "F.Cu" "F.Mask" "F.Paste")
			(net "M_A_CPU0_SB_DQS_DP<2>")
		)
		(pad "C23" smd circle
			(at -19.519392 -26.134314 270)
			(size 0.4318 0.4318)
			(layers "F.Cu" "F.Mask" "F.Paste")
			(net "M_A_CPU0_SB_DQ<16>")
		)
		(pad "C25" smd circle
			(at -17.89176 -26.134314 270)
			(size 0.4318 0.4318)
			(layers "F.Cu" "F.Mask" "F.Paste")
			(net "M_A_CPU0_SB_DQ<13>")
		)
		(pad "C27" smd circle
			(at -16.263874 -26.134314 270)
			(size 0.4318 0.4318)
			(layers "F.Cu" "F.Mask" "F.Paste")
			(net "M_A_CPU0_SB_DQS_DP<1>")
		)
		(pad "C29" smd circle
			(at -14.635988 -26.134314 270)
			(size 0.4318 0.4318)
			(layers "F.Cu" "F.Mask" "F.Paste")
			(net "M_A_CPU0_SB_DQ<8>")
		)
		(pad "C31" smd circle
			(at -13.008356 -26.134314 270)
			(size 0.4318 0.4318)
			(layers "F.Cu" "F.Mask" "F.Paste")
			(net "M_A_CPU0_SB_CB<1>")
		)
		(pad "C33" smd circle
			(at -11.380724 -26.134314 270)
			(size 0.4318 0.4318)
			(layers "F.Cu" "F.Mask" "F.Paste")
			(net "M_A_CPU0_SB_DQS_DP<9>")
		)
		(pad "C35" smd circle
			(at -9.752838 -26.134314 270)
			(size 0.4318 0.4318)
			(layers "F.Cu" "F.Mask" "F.Paste")
			(net "M_A_CPU0_SB_CB<4>")
		)
		(pad "C37" smd circle
			(at -8.124952 -26.134314 270)
			(size 0.4318 0.4318)
			(layers "F.Cu" "F.Mask" "F.Paste")
			(net "M_A_CPU0_SB_CS_N<1>")
		)
		(pad "C39" smd circle
			(at -6.49732 -26.134314 270)
			(size 0.4318 0.4318)
			(layers "F.Cu" "F.Mask" "F.Paste")
			(net "GND")
		)
		(pad "C41" smd circle
			(at -4.869434 -26.134314 270)
			(size 0.4318 0.4318)
			(layers "F.Cu" "F.Mask" "F.Paste")
			(net "M_A_CPU0_SB_CA<2>")
		)
		(pad "C43" smd circle
			(at -3.241802 -26.134314 270)
			(size 0.4318 0.4318)
			(layers "F.Cu" "F.Mask" "F.Paste")
			(net "M_A_CPU0_CLK_DP<0>")
		)
		(pad "C45" smd oval
			(at -1.613916 -26.134314 45)
			(size 0.381 0.4826)
			(drill
				(offset 0 -0.0508)
			)
			(layers "F.Cu" "F.Mask" "F.Paste")
			(net "GND")
		)
		(pad "C48" smd oval
			(at 2.427732 -26.024586 135)
			(size 0.381 0.4826)
			(drill
				(offset 0 -0.0508)
			)
			(layers "F.Cu" "F.Mask" "F.Paste")
			(net "M_A_CPU0_SA_CA<6>")
		)
		(pad "C50" smd circle
			(at 4.055618 -26.024586 270)
			(size 0.4318 0.4318)
			(layers "F.Cu" "F.Mask" "F.Paste")
			(net "M_A_CPU0_SA_CA<4>")
		)
		(pad "C52" smd circle
			(at 5.68325 -26.024586 270)
			(size 0.4318 0.4318)
			(layers "F.Cu" "F.Mask" "F.Paste")
			(net "GND")
		)
		(pad "C54" smd circle
			(at 7.311136 -26.024586 270)
			(size 0.4318 0.4318)
			(layers "F.Cu" "F.Mask" "F.Paste")
			(net "M_A_CPU0_SA_CS_N<0>")
		)
		(pad "C56" smd circle
			(at 8.939022 -26.024586 270)
			(size 0.4318 0.4318)
			(layers "F.Cu" "F.Mask" "F.Paste")
			(net "M_A_CPU0_SA_CB<5>")
		)
		(pad "C58" smd circle
			(at 10.566654 -26.024586 270)
			(size 0.4318 0.4318)
			(layers "F.Cu" "F.Mask" "F.Paste")
			(net "M_A_CPU0_SA_DQS_DP<4>")
		)
		(pad "C60" smd circle
			(at 12.19454 -26.024586 270)
			(size 0.4318 0.4318)
			(layers "F.Cu" "F.Mask" "F.Paste")
			(net "M_A_CPU0_SA_CB<0>")
		)
		(pad "C62" smd circle
			(at 13.822426 -26.024586 270)
			(size 0.4318 0.4318)
			(layers "F.Cu" "F.Mask" "F.Paste")
			(net "M_A_CPU0_SA_DQ<29>")
		)
		(pad "C64" smd circle
			(at 15.450058 -26.024586 270)
			(size 0.4318 0.4318)
			(layers "F.Cu" "F.Mask" "F.Paste")
			(net "M_A_CPU0_SA_DQS_DP<3>")
		)
		(pad "C66" smd circle
			(at 17.07769 -26.024586 270)
			(size 0.4318 0.4318)
			(layers "F.Cu" "F.Mask" "F.Paste")
			(net "M_A_CPU0_SA_DQ<24>")
		)
		(pad "C68" smd circle
			(at 18.705576 -26.024586 270)
			(size 0.4318 0.4318)
			(layers "F.Cu" "F.Mask" "F.Paste")
			(net "M_A_CPU0_SA_DQ<21>")
		)
		(pad "C70" smd circle
			(at 20.333462 -26.024586 270)
			(size 0.4318 0.4318)
			(layers "F.Cu" "F.Mask" "F.Paste")
			(net "M_A_CPU0_SA_DQS_DP<2>")
		)
		(pad "C72" smd circle
			(at 21.961094 -26.024586 270)
			(size 0.4318 0.4318)
			(layers "F.Cu" "F.Mask" "F.Paste")
			(net "GND")
		)
		(pad "C74" smd circle
			(at 23.58898 -26.024586 270)
			(size 0.4318 0.4318)
			(layers "F.Cu" "F.Mask" "F.Paste")
			(net "GND")
		)
		(pad "C76" smd circle
			(at 25.216612 -26.024586 270)
			(size 0.4318 0.4318)
			(layers "F.Cu" "F.Mask" "F.Paste")
			(net "M_A_CPU0_SA_DQ<4>")
		)
		(pad "C78" smd circle
			(at 26.844498 -26.024586 270)
			(size 0.4318 0.4318)
			(layers "F.Cu" "F.Mask" "F.Paste")
			(net "GND")
		)
		(pad "C80" smd circle
			(at 28.472384 -26.024586 270)
			(size 0.4318 0.4318)
			(layers "F.Cu" "F.Mask" "F.Paste")
			(net "GND")
		)
		(pad "C82" smd circle
			(at 30.100016 -26.024586 270)
			(size 0.4318 0.4318)
			(layers "F.Cu" "F.Mask" "F.Paste")
			(net "GND")
		)
		(pad "C84" smd oval
			(at 31.727902 -26.024586 45)
			(size 0.381 0.4826)
			(drill
				(offset 0 -0.0508)
			)
			(layers "F.Cu" "F.Mask" "F.Paste")
			(net "PVCCFA_EHV_FIVRA_CPU0")
		)
		(pad "C86" smd oval
			(at 33.355534 -26.024586 45)
			(size 0.381 0.4826)
			(drill
				(offset 0 -0.0508)
			)
			(layers "F.Cu" "F.Mask" "F.Paste")
			(net "GND")
		)
		(pad "C88" smd oval
			(at 34.98342 -26.024586 45)
			(size 0.381 0.4826)
			(drill
				(offset 0 -0.0508)
			)
			(layers "F.Cu" "F.Mask" "F.Paste")
			(net "PVCCFA_EHV_FIVRA_CPU0")
		)
		(pad "CA3" smd circle
			(at -35.797236 1.119886 270)
			(size 0.4318 0.4318)
			(layers "F.Cu" "F.Mask" "F.Paste")
			(net "GND")
		)
		(pad "CA5" smd circle
			(at -34.169604 1.119886 270)
			(size 0.4318 0.4318)
			(layers "F.Cu" "F.Mask" "F.Paste")
			(net "UPI_CPU0_CPU1_P1P0_DN<22>")
		)
		(pad "CA7" smd circle
			(at -32.541718 1.119886 270)
			(size 0.4318 0.4318)
			(layers "F.Cu" "F.Mask" "F.Paste")
			(net "PVCCD_HV_CPU0")
		)
		(pad "CA9" smd circle
			(at -30.914086 1.119886 270)
			(size 0.4318 0.4318)
			(layers "F.Cu" "F.Mask" "F.Paste")
			(net "P5E_CPU0_PE1_RX_DP<6>")
		)
		(pad "CA11" smd circle
			(at -29.2862 1.119886 270)
			(size 0.4318 0.4318)
			(layers "F.Cu" "F.Mask" "F.Paste")
			(net "VSENSE_PVCCINFAON_CPU0_DP")
		)
		(pad "CA13" smd circle
			(at -27.658314 1.119886 270)
			(size 0.4318 0.4318)
			(layers "F.Cu" "F.Mask" "F.Paste")
			(net "P5E_CPU0_PE1_TX_DN<7>")
		)
		(pad "CA15" smd circle
			(at -26.030682 1.119886 270)
			(size 0.4318 0.4318)
			(layers "F.Cu" "F.Mask" "F.Paste")
			(net "PVCCINFAON_CPU0")
		)
		(pad "CA17" smd circle
			(at -24.402796 1.119886 270)
			(size 0.4318 0.4318)
			(layers "F.Cu" "F.Mask" "F.Paste")
			(net "DMI_CPU0_PCH_TX_DP<1>")
		)
		(pad "CA19" smd circle
			(at -22.77491 1.119886 270)
			(size 0.4318 0.4318)
			(layers "F.Cu" "F.Mask" "F.Paste")
			(net "DMI_CPU0_PCH_TX_DN<0>")
		)
		(pad "CA21" smd circle
			(at -21.147278 1.119886 270)
			(size 0.4318 0.4318)
			(layers "F.Cu" "F.Mask" "F.Paste")
			(net "NC_CPU0_DMI_APROBE<0>")
		)
		(pad "CA23" smd circle
			(at -19.519392 1.119886 270)
			(size 0.4318 0.4318)
			(layers "F.Cu" "F.Mask" "F.Paste")
			(net "NC_CPU0_UPI1_APROBE<1>")
		)
		(pad "CA25" smd circle
			(at -17.89176 1.119886 270)
			(size 0.4318 0.4318)
			(layers "F.Cu" "F.Mask" "F.Paste")
			(net "SMB_PEHPCPU0_GTL_SCL")
		)
		(pad "CA27" smd circle
			(at -16.263874 1.119886 270)
			(size 0.4318 0.4318)
			(layers "F.Cu" "F.Mask" "F.Paste")
			(net "TP_TRC_CPU0_PTI<6>")
		)
		(pad "CA29" smd circle
			(at -14.635988 1.119886 270)
			(size 0.4318 0.4318)
			(layers "F.Cu" "F.Mask" "F.Paste")
			(net "TP_TRC_CPU0_PTI<4>")
		)
		(pad "CA31" smd circle
			(at -13.008356 1.119886 270)
			(size 0.4318 0.4318)
			(layers "F.Cu" "F.Mask" "F.Paste")
			(net "GND")
		)
		(pad "CA33" smd circle
			(at -11.380724 1.119886 270)
			(size 0.4318 0.4318)
			(layers "F.Cu" "F.Mask" "F.Paste")
			(net "PVCCIN_CPU0")
		)
		(pad "CA35" smd circle
			(at -9.752838 1.119886 270)
			(size 0.4318 0.4318)
			(layers "F.Cu" "F.Mask" "F.Paste")
			(net "PVCCIN_CPU0")
		)
		(pad "CA37" smd circle
			(at -8.124952 1.119886 270)
			(size 0.4318 0.4318)
			(layers "F.Cu" "F.Mask" "F.Paste")
			(net "PVCCIN_CPU0")
		)
		(pad "CA39" smd circle
			(at -6.49732 1.119886 270)
			(size 0.4318 0.4318)
			(layers "F.Cu" "F.Mask" "F.Paste")
			(net "PVCCIN_CPU0")
		)
		(pad "CA41" smd circle
			(at -4.869434 1.119886 270)
			(size 0.4318 0.4318)
			(layers "F.Cu" "F.Mask" "F.Paste")
			(net "PVCCIN_CPU0")
		)
		(pad "CA43" smd circle
			(at -3.241802 1.119886 270)
			(size 0.4318 0.4318)
			(layers "F.Cu" "F.Mask" "F.Paste")
			(net "PVCCIN_CPU0")
		)
		(pad "CA45" smd circle
			(at -1.613916 1.119886 270)
			(size 0.4318 0.4318)
			(layers "F.Cu" "F.Mask" "F.Paste")
			(net "PVCCIN_CPU0")
		)
		(pad "CA48" smd circle
			(at 2.427732 1.229614 270)
			(size 0.4318 0.4318)
			(layers "F.Cu" "F.Mask" "F.Paste")
			(net "PVCCIN_CPU0")
		)
		(pad "CA50" smd circle
			(at 4.055618 1.229614 270)
			(size 0.4318 0.4318)
			(layers "F.Cu" "F.Mask" "F.Paste")
			(net "PVCCIN_CPU0")
		)
		(pad "CA52" smd circle
			(at 5.68325 1.229614 270)
			(size 0.4318 0.4318)
			(layers "F.Cu" "F.Mask" "F.Paste")
			(net "PVCCIN_CPU0")
		)
		(pad "CA54" smd circle
			(at 7.311136 1.229614 270)
			(size 0.4318 0.4318)
			(layers "F.Cu" "F.Mask" "F.Paste")
			(net "PVCCIN_CPU0")
		)
		(pad "CA56" smd circle
			(at 8.939022 1.229614 270)
			(size 0.4318 0.4318)
			(layers "F.Cu" "F.Mask" "F.Paste")
			(net "PVCCIN_CPU0")
		)
		(pad "CA58" smd circle
			(at 10.566654 1.229614 270)
			(size 0.4318 0.4318)
			(layers "F.Cu" "F.Mask" "F.Paste")
			(net "PVCCIN_CPU0")
		)
		(pad "CA60" smd circle
			(at 12.19454 1.229614 270)
			(size 0.4318 0.4318)
			(layers "F.Cu" "F.Mask" "F.Paste")
			(net "PVCCIN_CPU0")
		)
		(pad "CA62" smd circle
			(at 13.822426 1.229614 270)
			(size 0.4318 0.4318)
			(layers "F.Cu" "F.Mask" "F.Paste")
			(net "PVCCIN_CPU0")
		)
		(pad "CA64" smd circle
			(at 15.450058 1.229614 270)
			(size 0.4318 0.4318)
			(layers "F.Cu" "F.Mask" "F.Paste")
			(net "PVCCIN_CPU0")
		)
	)
)
